(kicad_pcb
	(version 20260206)
	(generator "pcbnew")
	(generator_version "10.0")
	(general
		(thickness 1.6)
		(legacy_teardrops no)
	)
	(paper "A4")
	(title_block
		(title "9054_F0T_PDB_BD_GPU_F_V04_1213_1550_OCP.brd")
		(comment 1 "Grand Teton / footprints 510-514 of 608")
	)
	(layers
		(0 "F.Cu" signal "TOP")
		(4 "In1.Cu" signal "GND")
		(6 "In2.Cu" signal "IN1")
		(8 "In3.Cu" signal "GND1")
		(10 "In4.Cu" signal "VCC")
		(12 "In5.Cu" signal "VCC1")
		(14 "In6.Cu" signal "GND2")
		(16 "In7.Cu" signal "IN2")
		(18 "In8.Cu" signal "GND3")
		(2 "B.Cu" signal "BOTTOM")
		(9 "F.Adhes" user "F.Adhesive")
		(11 "B.Adhes" user "B.Adhesive")
		(13 "F.Paste" user "Package Geometry/Pastemask Top")
		(15 "B.Paste" user "Package Geometry/Pastemask Bottom")
		(5 "F.SilkS" user "Ref Des/Silkscreen Top")
		(7 "B.SilkS" user "Ref Des/Silkscreen Bottom")
		(1 "F.Mask" user "Board Geometry/Soldermask Top")
		(3 "B.Mask" user "Board Geometry/Soldermask Bottom")
		(17 "Dwgs.User" user "User.Drawings")
		(19 "Cmts.User" user "User.Comments")
		(21 "Eco1.User" user "User.Eco1")
		(23 "Eco2.User" user "User.Eco2")
		(25 "Edge.Cuts" user "Board Geometry/Outline")
		(27 "Margin" user)
		(31 "F.CrtYd" user "Package Geometry/Place Bound Top")
		(29 "B.CrtYd" user "Package Geometry/Place Bound Bottom")
		(35 "F.Fab" user "Ref Des/Assembly Top")
		(33 "B.Fab" user "Ref Des/Assembly Bottom")
	)
	(footprint ""
		(layer "B.Cu")
		(at 151.0284 -62.865 -90)
		(property "Reference" "PR7004"
			(at 0 0 90)
			(layer "B.SilkS")
			(hide yes)
			(effects
				(font
					(size 1.27 1.27)
				)
				(justify mirror)
			)
		)
		(property "Value" ""
			(at 0 0 90)
			(layer "B.Fab")
			(effects
				(font
					(size 1.27 1.27)
				)
				(justify mirror)
			)
		)
		(duplicate_pad_numbers_are_jumpers no)
		(fp_line
			(start -1.651 0.8382)
			(end 1.651 0.8382)
			(stroke
				(width 0.1524)
				(type default)
			)
			(layer "B.SilkS")
		)
		(fp_line
			(start 1.651 0.8382)
			(end 1.651 -0.8382)
			(stroke
				(width 0.1524)
				(type default)
			)
			(layer "B.SilkS")
		)
		(fp_line
			(start -1.651 -0.8382)
			(end -1.651 0.8382)
			(stroke
				(width 0.1524)
				(type default)
			)
			(layer "B.SilkS")
		)
		(fp_line
			(start 1.651 -0.8382)
			(end -1.651 -0.8382)
			(stroke
				(width 0.1524)
				(type default)
			)
			(layer "B.SilkS")
		)
		(fp_line
			(start -1.560576 0.7366)
			(end -1.560576 -0.7366)
			(stroke
				(width 0.1)
				(type default)
			)
			(layer "B.Fab")
		)
		(fp_line
			(start -1.524 0.7366)
			(end -1.560576 0.7366)
			(stroke
				(width 0.1)
				(type default)
			)
			(layer "B.Fab")
		)
		(fp_line
			(start 1.524 0.7366)
			(end -1.524 0.7366)
			(stroke
				(width 0.1)
				(type default)
			)
			(layer "B.Fab")
		)
		(fp_line
			(start 1.559814 0.7366)
			(end 1.524 0.7366)
			(stroke
				(width 0.1)
				(type default)
			)
			(layer "B.Fab")
		)
		(fp_line
			(start -1.560576 -0.7366)
			(end -1.524 -0.7366)
			(stroke
				(width 0.1)
				(type default)
			)
			(layer "B.Fab")
		)
		(fp_line
			(start -1.524 -0.7366)
			(end 1.524 -0.7366)
			(stroke
				(width 0.1)
				(type default)
			)
			(layer "B.Fab")
		)
		(fp_line
			(start 1.524 -0.7366)
			(end 1.559814 -0.7366)
			(stroke
				(width 0.1)
				(type default)
			)
			(layer "B.Fab")
		)
		(fp_line
			(start 1.559814 -0.7366)
			(end 1.559814 0.7366)
			(stroke
				(width 0.1)
				(type default)
			)
			(layer "B.Fab")
		)
		(pad "1" smd rect
			(at 0.94996 0 270)
			(size 1.1176 1.3716)
			(layers "B.Cu" "B.Mask" "B.Paste")
			(net "P52V_HS2")
		)
		(pad "2" smd rect
			(at -0.94996 0 270)
			(size 1.1176 1.3716)
			(layers "B.Cu" "B.Mask" "B.Paste")
			(net "P52V_HS2_VDSFB")
		)
	)
	(footprint ""
		(layer "B.Cu")
		(at 338.8614 -39.243 -90)
		(property "Reference" "PD16"
			(at 3.937 1.44907 270)
			(unlocked yes)
			(layer "B.SilkS")
			(effects
				(font
					(size 0.7874 0.5842)
					(thickness 0.1524)
				)
				(justify left mirror)
			)
		)
		(property "Value" ""
			(at 0 0 90)
			(layer "B.Fab")
			(effects
				(font
					(size 1.27 1.27)
				)
				(justify mirror)
			)
		)
		(duplicate_pad_numbers_are_jumpers no)
		(fp_line
			(start -2.032 0.7112)
			(end 1.651 0.7112)
			(stroke
				(width 0.1524)
				(type default)
			)
			(layer "B.SilkS")
		)
		(fp_line
			(start 1.651 0.7112)
			(end 1.651 -0.7112)
			(stroke
				(width 0.1524)
				(type default)
			)
			(layer "B.SilkS")
		)
		(fp_line
			(start -1.778 0.6858)
			(end -1.778 -0.6858)
			(stroke
				(width 0.1524)
				(type default)
			)
			(layer "B.SilkS")
		)
		(fp_line
			(start 0.299974 0.500126)
			(end -0.199898 0)
			(stroke
				(width 0.1524)
				(type default)
			)
			(layer "B.SilkS")
		)
		(fp_line
			(start -0.199898 0)
			(end 0.299974 -0.500126)
			(stroke
				(width 0.1524)
				(type default)
			)
			(layer "B.SilkS")
		)
		(fp_line
			(start -0.299974 -0.500126)
			(end -0.299974 0.500126)
			(stroke
				(width 0.1524)
				(type default)
			)
			(layer "B.SilkS")
		)
		(fp_line
			(start 0.299974 -0.500126)
			(end 0.299974 0.500126)
			(stroke
				(width 0.1524)
				(type default)
			)
			(layer "B.SilkS")
		)
		(fp_line
			(start -1.905 -0.6858)
			(end -1.905 0.6858)
			(stroke
				(width 0.1524)
				(type default)
			)
			(layer "B.SilkS")
		)
		(fp_line
			(start -1.651 -0.6858)
			(end -1.651 0.6858)
			(stroke
				(width 0.1524)
				(type default)
			)
			(layer "B.SilkS")
		)
		(fp_line
			(start -2.032 -0.7112)
			(end -2.032 0.7112)
			(stroke
				(width 0.1524)
				(type default)
			)
			(layer "B.SilkS")
		)
		(fp_line
			(start 1.651 -0.7112)
			(end -2.032 -0.7112)
			(stroke
				(width 0.1524)
				(type default)
			)
			(layer "B.SilkS")
		)
		(fp_line
			(start -0.899922 0.700024)
			(end 0.899922 0.700024)
			(stroke
				(width 0.1)
				(type default)
			)
			(layer "B.Fab")
		)
		(fp_line
			(start 0.899922 0.700024)
			(end 0.899922 0.175006)
			(stroke
				(width 0.1)
				(type default)
			)
			(layer "B.Fab")
		)
		(fp_line
			(start 0.299974 0.500126)
			(end -0.199898 0)
			(stroke
				(width 0.1)
				(type default)
			)
			(layer "B.Fab")
		)
		(fp_line
			(start -1.35001 0.175006)
			(end -0.899922 0.175006)
			(stroke
				(width 0.1)
				(type default)
			)
			(layer "B.Fab")
		)
		(fp_line
			(start -0.899922 0.175006)
			(end -0.899922 0.700024)
			(stroke
				(width 0.1)
				(type default)
			)
			(layer "B.Fab")
		)
		(fp_line
			(start 0.899922 0.175006)
			(end 1.35001 0.175006)
			(stroke
				(width 0.1)
				(type default)
			)
			(layer "B.Fab")
		)
		(fp_line
			(start 1.35001 0.175006)
			(end 1.35001 -0.225044)
			(stroke
				(width 0.1)
				(type default)
			)
			(layer "B.Fab")
		)
		(fp_line
			(start -0.199898 0)
			(end 0.299974 -0.500126)
			(stroke
				(width 0.1)
				(type default)
			)
			(layer "B.Fab")
		)
		(fp_line
			(start -1.35001 -0.225044)
			(end -1.35001 0.175006)
			(stroke
				(width 0.1)
				(type default)
			)
			(layer "B.Fab")
		)
		(fp_line
			(start -0.899922 -0.225044)
			(end -1.35001 -0.225044)
			(stroke
				(width 0.1)
				(type default)
			)
			(layer "B.Fab")
		)
		(fp_line
			(start 0.899922 -0.225044)
			(end 0.899922 -0.700024)
			(stroke
				(width 0.1)
				(type default)
			)
			(layer "B.Fab")
		)
		(fp_line
			(start 1.35001 -0.225044)
			(end 0.899922 -0.225044)
			(stroke
				(width 0.1)
				(type default)
			)
			(layer "B.Fab")
		)
		(fp_line
			(start -0.299974 -0.500126)
			(end -0.299974 0.500126)
			(stroke
				(width 0.1)
				(type default)
			)
			(layer "B.Fab")
		)
		(fp_line
			(start 0.299974 -0.500126)
			(end 0.299974 0.500126)
			(stroke
				(width 0.1)
				(type default)
			)
			(layer "B.Fab")
		)
		(fp_line
			(start -0.899922 -0.700024)
			(end -0.899922 -0.225044)
			(stroke
				(width 0.1)
				(type default)
			)
			(layer "B.Fab")
		)
		(fp_line
			(start 0.899922 -0.700024)
			(end -0.899922 -0.700024)
			(stroke
				(width 0.1)
				(type default)
			)
			(layer "B.Fab")
		)
		(fp_text user "+"
			(at 3.556 -0.19685 270)
			(unlocked yes)
			(layer "B.SilkS")
			(effects
				(font
					(size 1.905 1.4224)
					(thickness 0.1524)
				)
				(justify left mirror)
			)
		)
		(fp_text user "-"
			(at -1.8288 -0.24765 270)
			(unlocked yes)
			(layer "B.SilkS")
			(effects
				(font
					(size 1.905 1.4224)
					(thickness 0.1524)
				)
				(justify left mirror)
			)
		)
		(fp_text user "+"
			(at 2.794 -0.19685 270)
			(unlocked yes)
			(layer "B.Fab")
			(effects
				(font
					(size 1.905 1.4224)
					(thickness 0.1524)
				)
				(justify left mirror)
			)
		)
		(fp_text user "-"
			(at -1.8288 -0.24765 270)
			(unlocked yes)
			(layer "B.Fab")
			(effects
				(font
					(size 1.905 1.4224)
					(thickness 0.1524)
				)
				(justify left mirror)
			)
		)
		(pad "1" smd rect
			(at 1.0922 0 270)
			(size 0.8128 0.8636)
			(layers "B.Cu" "B.Mask" "B.Paste")
			(net "P52V_HS1_4287_GATE2_R")
		)
		(pad "2" smd rect
			(at -1.0922 0 90)
			(size 0.8128 0.8636)
			(layers "B.Cu" "B.Mask" "B.Paste")
			(net "P52V_HS1_GATE2_R1")
		)
	)
	(footprint ""
		(layer "B.Cu")
		(at 169.210736 -74.295 180)
		(property "Reference" "R5882"
			(at 0 0 0)
			(layer "B.SilkS")
			(hide yes)
			(effects
				(font
					(size 1.27 1.27)
				)
				(justify mirror)
			)
		)
		(property "Value" ""
			(at 0 0 0)
			(layer "B.Fab")
			(effects
				(font
					(size 1.27 1.27)
				)
				(justify mirror)
			)
		)
		(duplicate_pad_numbers_are_jumpers no)
		(fp_line
			(start 0.7874 0.4064)
			(end 0.7874 -0.4064)
			(stroke
				(width 0.1524)
				(type default)
			)
			(layer "B.SilkS")
		)
		(fp_line
			(start 0.7874 -0.4064)
			(end -0.7874 -0.4064)
			(stroke
				(width 0.1524)
				(type default)
			)
			(layer "B.SilkS")
		)
		(fp_line
			(start -0.7874 0.4064)
			(end 0.7874 0.4064)
			(stroke
				(width 0.1524)
				(type default)
			)
			(layer "B.SilkS")
		)
		(fp_line
			(start -0.7874 -0.4064)
			(end -0.7874 0.4064)
			(stroke
				(width 0.1524)
				(type default)
			)
			(layer "B.SilkS")
		)
		(fp_line
			(start 0.67945 0.3048)
			(end 0.67945 -0.305054)
			(stroke
				(width 0.1)
				(type default)
			)
			(layer "B.Fab")
		)
		(fp_line
			(start 0.67945 -0.305054)
			(end 0.12065 -0.305054)
			(stroke
				(width 0.1)
				(type default)
			)
			(layer "B.Fab")
		)
		(fp_line
			(start 0.12065 0.3048)
			(end 0.67945 0.3048)
			(stroke
				(width 0.1)
				(type default)
			)
			(layer "B.Fab")
		)
		(fp_line
			(start 0.12065 0.2794)
			(end 0.12065 0.3048)
			(stroke
				(width 0.1)
				(type default)
			)
			(layer "B.Fab")
		)
		(fp_line
			(start 0.12065 -0.2794)
			(end -0.12065 -0.2794)
			(stroke
				(width 0.1)
				(type default)
			)
			(layer "B.Fab")
		)
		(fp_line
			(start 0.12065 -0.305054)
			(end 0.12065 -0.2794)
			(stroke
				(width 0.1)
				(type default)
			)
			(layer "B.Fab")
		)
		(fp_line
			(start -0.120396 0.3048)
			(end -0.120396 0.2794)
			(stroke
				(width 0.1)
				(type default)
			)
			(layer "B.Fab")
		)
		(fp_line
			(start -0.120396 0.2794)
			(end 0.12065 0.2794)
			(stroke
				(width 0.1)
				(type default)
			)
			(layer "B.Fab")
		)
		(fp_line
			(start -0.12065 -0.2794)
			(end -0.12065 -0.3048)
			(stroke
				(width 0.1)
				(type default)
			)
			(layer "B.Fab")
		)
		(fp_line
			(start -0.12065 -0.3048)
			(end -0.67945 -0.3048)
			(stroke
				(width 0.1)
				(type default)
			)
			(layer "B.Fab")
		)
		(fp_line
			(start -0.67945 0.3048)
			(end -0.120396 0.3048)
			(stroke
				(width 0.1)
				(type default)
			)
			(layer "B.Fab")
		)
		(fp_line
			(start -0.67945 -0.3048)
			(end -0.67945 0.3048)
			(stroke
				(width 0.1)
				(type default)
			)
			(layer "B.Fab")
		)
		(pad "1" smd circle
			(at 0.40005 0)
			(size 0 0)
			(layers "B.Cu" "B.Mask" "B.Paste")
			(net "SMB_P52V_PDB_SDA")
		)
		(pad "2" smd circle
			(at -0.40005 0)
			(size 0 0)
			(layers "B.Cu" "B.Mask" "B.Paste")
			(net "SMB_CM_HS2_3V3SB_DATI")
		)
	)
	(footprint ""
		(layer "B.Cu")
		(at 282.575 -91.567 -90)
		(property "Reference" "R5904"
			(at 0 0 90)
			(layer "B.SilkS")
			(hide yes)
			(effects
				(font
					(size 1.27 1.27)
				)
				(justify mirror)
			)
		)
		(property "Value" ""
			(at 0 0 90)
			(layer "B.Fab")
			(effects
				(font
					(size 1.27 1.27)
				)
				(justify mirror)
			)
		)
		(duplicate_pad_numbers_are_jumpers no)
		(fp_line
			(start -0.7874 0.4064)
			(end 0.7874 0.4064)
			(stroke
				(width 0.1524)
				(type default)
			)
			(layer "B.SilkS")
		)
		(fp_line
			(start 0.7874 0.4064)
			(end 0.7874 -0.4064)
			(stroke
				(width 0.1524)
				(type default)
			)
			(layer "B.SilkS")
		)
		(fp_line
			(start -0.7874 -0.4064)
			(end -0.7874 0.4064)
			(stroke
				(width 0.1524)
				(type default)
			)
			(layer "B.SilkS")
		)
		(fp_line
			(start 0.7874 -0.4064)
			(end -0.7874 -0.4064)
			(stroke
				(width 0.1524)
				(type default)
			)
			(layer "B.SilkS")
		)
		(fp_line
			(start -0.67945 0.3048)
			(end -0.120396 0.3048)
			(stroke
				(width 0.1)
				(type default)
			)
			(layer "B.Fab")
		)
		(fp_line
			(start -0.120396 0.3048)
			(end -0.120396 0.2794)
			(stroke
				(width 0.1)
				(type default)
			)
			(layer "B.Fab")
		)
		(fp_line
			(start 0.12065 0.3048)
			(end 0.67945 0.3048)
			(stroke
				(width 0.1)
				(type default)
			)
			(layer "B.Fab")
		)
		(fp_line
			(start 0.67945 0.3048)
			(end 0.67945 -0.305054)
			(stroke
				(width 0.1)
				(type default)
			)
			(layer "B.Fab")
		)
		(fp_line
			(start -0.120396 0.2794)
			(end 0.12065 0.2794)
			(stroke
				(width 0.1)
				(type default)
			)
			(layer "B.Fab")
		)
		(fp_line
			(start 0.12065 0.2794)
			(end 0.12065 0.3048)
			(stroke
				(width 0.1)
				(type default)
			)
			(layer "B.Fab")
		)
		(fp_line
			(start -0.12065 -0.2794)
			(end -0.12065 -0.3048)
			(stroke
				(width 0.1)
				(type default)
			)
			(layer "B.Fab")
		)
		(fp_line
			(start 0.12065 -0.2794)
			(end -0.12065 -0.2794)
			(stroke
				(width 0.1)
				(type default)
			)
			(layer "B.Fab")
		)
		(fp_line
			(start -0.67945 -0.3048)
			(end -0.67945 0.3048)
			(stroke
				(width 0.1)
				(type default)
			)
			(layer "B.Fab")
		)
		(fp_line
			(start -0.12065 -0.3048)
			(end -0.67945 -0.3048)
			(stroke
				(width 0.1)
				(type default)
			)
			(layer "B.Fab")
		)
		(fp_line
			(start 0.12065 -0.305054)
			(end 0.12065 -0.2794)
			(stroke
				(width 0.1)
				(type default)
			)
			(layer "B.Fab")
		)
		(fp_line
			(start 0.67945 -0.305054)
			(end 0.12065 -0.305054)
			(stroke
				(width 0.1)
				(type default)
			)
			(layer "B.Fab")
		)
		(pad "1" smd circle
			(at 0.40005 0 90)
			(size 0 0)
			(layers "B.Cu" "B.Mask" "B.Paste")
			(net "FM_HS1_EN_BUSBAR")
		)
		(pad "2" smd circle
			(at -0.40005 0 90)
			(size 0 0)
			(layers "B.Cu" "B.Mask" "B.Paste")
			(net "GND")
		)
	)
	(footprint ""
		(layer "B.Cu")
		(at 168.829736 -65.659)
		(property "Reference" "PC610"
			(at 0 0 0)
			(layer "B.SilkS")
			(hide yes)
			(effects
				(font
					(size 1.27 1.27)
				)
				(justify mirror)
			)
		)
		(property "Value" ""
			(at 0 0 0)
			(layer "B.Fab")
			(effects
				(font
					(size 1.27 1.27)
				)
				(justify mirror)
			)
		)
		(duplicate_pad_numbers_are_jumpers no)
		(fp_line
			(start -0.7874 -0.4064)
			(end -0.7874 0.4064)
			(stroke
				(width 0.1524)
				(type default)
			)
			(layer "B.SilkS")
		)
		(fp_line
			(start -0.7874 0.4064)
			(end 0.7874 0.4064)
			(stroke
				(width 0.1524)
				(type default)
			)
			(layer "B.SilkS")
		)
		(fp_line
			(start 0.7874 -0.4064)
			(end -0.7874 -0.4064)
			(stroke
				(width 0.1524)
				(type default)
			)
			(layer "B.SilkS")
		)
		(fp_line
			(start 0.7874 0.4064)
			(end 0.7874 -0.4064)
			(stroke
				(width 0.1524)
				(type default)
			)
			(layer "B.SilkS")
		)
		(fp_line
			(start -0.67945 -0.3048)
			(end -0.67945 0.3048)
			(stroke
				(width 0.1)
				(type default)
			)
			(layer "B.Fab")
		)
		(fp_line
			(start -0.67945 0.3048)
			(end -0.120396 0.3048)
			(stroke
				(width 0.1)
				(type default)
			)
			(layer "B.Fab")
		)
		(fp_line
			(start -0.12065 -0.3048)
			(end -0.67945 -0.3048)
			(stroke
				(width 0.1)
				(type default)
			)
			(layer "B.Fab")
		)
		(fp_line
			(start -0.12065 -0.2794)
			(end -0.12065 -0.3048)
			(stroke
				(width 0.1)
				(type default)
			)
			(layer "B.Fab")
		)
		(fp_line
			(start -0.120396 0.2794)
			(end 0.12065 0.2794)
			(stroke
				(width 0.1)
				(type default)
			)
			(layer "B.Fab")
		)
		(fp_line
			(start -0.120396 0.3048)
			(end -0.120396 0.2794)
			(stroke
				(width 0.1)
				(type default)
			)
			(layer "B.Fab")
		)
		(fp_line
			(start 0.12065 -0.305054)
			(end 0.12065 -0.2794)
			(stroke
				(width 0.1)
				(type default)
			)
			(layer "B.Fab")
		)
		(fp_line
			(start 0.12065 -0.2794)
			(end -0.12065 -0.2794)
			(stroke
				(width 0.1)
				(type default)
			)
			(layer "B.Fab")
		)
		(fp_line
			(start 0.12065 0.2794)
			(end 0.12065 0.3048)
			(stroke
				(width 0.1)
				(type default)
			)
			(layer "B.Fab")
		)
		(fp_line
			(start 0.12065 0.3048)
			(end 0.67945 0.3048)
			(stroke
				(width 0.1)
				(type default)
			)
			(layer "B.Fab")
		)
		(fp_line
			(start 0.67945 -0.305054)
			(end 0.12065 -0.305054)
			(stroke
				(width 0.1)
				(type default)
			)
			(layer "B.Fab")
		)
		(fp_line
			(start 0.67945 0.3048)
			(end 0.67945 -0.305054)
			(stroke
				(width 0.1)
				(type default)
			)
			(layer "B.Fab")
		)
		(pad "1" smd circle
			(at 0.40005 0 180)
			(size 0 0)
			(layers "B.Cu" "B.Mask" "B.Paste")
			(net "P52V_HS2_ISET")
		)
		(pad "2" smd circle
			(at -0.40005 0 180)
			(size 0 0)
			(layers "B.Cu" "B.Mask" "B.Paste")
			(net "GND1_FIELD_SIGNAL")
		)
	)
)
